# BASEBOARD_FAB2 (Tioga Pass) — schematic netlist excerpt (pin names and nets, part order shuffled) for the footprints in the layout excerpt that follows; sources: Cadence DE-HDL packaged netlist, KiCad conversion of Wiwynn_Tioga_Pass_MB.brd

T1D17  TEST-PAD-12P-1-GP-U  pkg DISCRET-GB1  page 258
  DP  = L5_85OHM_10INCH_DP
  DN  = L5_85OHM_10INCH_DN
  GND(0)  = GND
  GND(1)  = GND
  GND(2)  = GND
  GND(3)  = GND
  GND(4)  = GND
  GND(5)  = GND
  GND(6)  = GND
  GND(7)  = GND
  GND(8)  = GND
  GND(9)  = GND

R9F66  RES  0.0 5% EMPTY  pkg 0402  page 158 : A = SP2_BMC_CM_UART_TX ; B = SP2_BMC_CM_UART_TX_R

(kicad_pcb
	(version 20260206)
	(generator "pcbnew")
	(generator_version "10.0")
	(general
		(thickness 1.6)
		(legacy_teardrops no)
	)
	(paper "A4")
	(title_block
		(title "Wiwynn_Tioga_Pass_MB.brd")
		(comment 1 "Tioga Pass / footprints 4401-4402 of 4770")
	)
	(layers
		(0 "F.Cu" signal "TOP")
		(4 "In1.Cu" signal "L2GND")
		(6 "In2.Cu" signal "L3")
		(8 "In3.Cu" signal "L4GND")
		(10 "In4.Cu" signal "L5")
		(12 "In5.Cu" signal "L6GND")
		(14 "In6.Cu" signal "L7VCC")
		(16 "In7.Cu" signal "L8VCC")
		(18 "In8.Cu" signal "L9GND")
		(20 "In9.Cu" signal "L10")
		(22 "In10.Cu" signal "L11GND")
		(24 "In11.Cu" signal "L12")
		(26 "In12.Cu" signal "L13GND")
		(2 "B.Cu" signal "BOTTOM")
		(9 "F.Adhes" user "F.Adhesive")
		(11 "B.Adhes" user "B.Adhesive")
		(13 "F.Paste" user "Package Geometry/Pastemask Top")
		(15 "B.Paste" user "Package Geometry/Pastemask Bottom")
		(5 "F.SilkS" user "Ref Des/Silkscreen Top")
		(7 "B.SilkS" user "Ref Des/Silkscreen Bottom")
		(1 "F.Mask" user "Board Geometry/Soldermask Top")
		(3 "B.Mask" user "Board Geometry/Soldermask Bottom")
		(17 "Dwgs.User" user "User.Drawings")
		(19 "Cmts.User" user "User.Comments")
		(21 "Eco1.User" user "User.Eco1")
		(23 "Eco2.User" user "User.Eco2")
		(25 "Edge.Cuts" user "Board Geometry/Outline")
		(27 "Margin" user)
		(31 "F.CrtYd" user "Package Geometry/Place Bound Top")
		(29 "B.CrtYd" user "Package Geometry/Place Bound Bottom")
		(35 "F.Fab" user "Ref Des/Assembly Top")
		(33 "B.Fab" user "Ref Des/Assembly Bottom")
	)
	(footprint ""
		(layer "B.Cu")
		(at 497.743226 -34.715704 90)
		(property "Reference" "R9F66"
			(at 0 0 90)
			(layer "B.SilkS")
			(hide yes)
			(effects
				(font
					(size 1.27 1.27)
				)
				(justify mirror)
			)
		)
		(property "Value" ""
			(at 0 0 90)
			(layer "B.Fab")
			(effects
				(font
					(size 1.27 1.27)
				)
				(justify mirror)
			)
		)
		(duplicate_pad_numbers_are_jumpers no)
		(fp_poly
			(pts
				(xy 0.2794 -0.1016) (xy -0.2794 -0.1016) (xy -0.2794 0.9906) (xy 0.2794 0.9906)
			)
			(stroke
				(width 0)
				(type default)
			)
			(fill no)
			(layer "B.CrtYd")
		)
		(fp_line
			(start 0.2794 -0.1016)
			(end 0.2794 0.9906)
			(stroke
				(width 0.1)
				(type default)
			)
			(layer "B.Fab")
		)
		(fp_line
			(start -0.2794 -0.1016)
			(end 0.2794 -0.1016)
			(stroke
				(width 0.1)
				(type default)
			)
			(layer "B.Fab")
		)
		(fp_line
			(start 0.2794 0.9906)
			(end -0.2794 0.9906)
			(stroke
				(width 0.1)
				(type default)
			)
			(layer "B.Fab")
		)
		(fp_line
			(start -0.2794 0.9906)
			(end -0.2794 -0.1016)
			(stroke
				(width 0.1)
				(type default)
			)
			(layer "B.Fab")
		)
		(pad "1" smd rect
			(at 0 0 270)
			(size 0.508 0.508)
			(layers "B.Cu" "B.Mask" "B.Paste")
			(net "SP2_BMC_CM_UART_TX")
		)
		(pad "2" smd rect
			(at 0 0.889 270)
			(size 0.508 0.508)
			(layers "B.Cu" "B.Mask" "B.Paste")
			(net "SP2_BMC_CM_UART_TX_R")
		)
		(zone
			(layer "B.Cu")
			(hatch none 0.5)
			(connect_pads
				(clearance 0)
			)
			(min_thickness 0.25)
			(keepout
				(tracks allowed)
				(vias not_allowed)
				(pads allowed)
				(copperpour not_allowed)
				(footprints allowed)
			)
			(placement
				(enabled no)
				(sheetname "")
			)
			(fill
				(thermal_gap 0.5)
				(thermal_bridge_width 0.5)
				(island_removal_mode 0)
			)
			(polygon
				(pts
					(xy 497.997226 -34.969704) (xy 497.997226 -34.461704) (xy 498.378226 -34.461704) (xy 498.378226 -34.969704)
				)
			)
		)
		(zone
			(layer "B.Cu")
			(hatch none 0.5)
			(connect_pads
				(clearance 0)
			)
			(min_thickness 0.25)
			(keepout
				(tracks not_allowed)
				(vias allowed)
				(pads allowed)
				(copperpour not_allowed)
				(footprints allowed)
			)
			(placement
				(enabled no)
				(sheetname "")
			)
			(fill
				(thermal_gap 0.5)
				(thermal_bridge_width 0.5)
				(island_removal_mode 0)
			)
			(polygon
				(pts
					(xy 498.378226 -34.969704) (xy 498.378226 -34.461704) (xy 497.997226 -34.461704) (xy 497.997226 -34.969704)
				)
			)
		)
	)
	(footprint ""
		(layer "B.Cu")
		(at 316.3443 -164.9095 -90)
		(property "Reference" "T1D17"
			(at 0 0 90)
			(layer "B.SilkS")
			(hide yes)
			(effects
				(font
					(size 1.27 1.27)
				)
				(justify mirror)
			)
		)
		(property "Value" "*"
			(at 3.4036 -4.46405 270)
			(unlocked yes)
			(layer "B.Fab")
			(hide yes)
			(effects
				(font
					(size 0.889 0.889)
					(thickness 0.1524)
				)
				(justify mirror)
			)
		)
		(property "Device Type" "TEST-PAD-12P-1-GP-U_DISCRET-GBA"
			(at 3.4036 -5.98805 270)
			(unlocked yes)
			(layer "B.Fab")
			(hide yes)
			(effects
				(font
					(size 0.889 0.889)
					(thickness 0.1524)
				)
				(justify mirror)
			)
		)
		(duplicate_pad_numbers_are_jumpers no)
		(fp_line
			(start -2.3622 3.4798)
			(end 2.3876 3.4798)
			(stroke
				(width 0.1524)
				(type default)
			)
			(layer "B.SilkS")
		)
		(fp_line
			(start 2.3876 3.4798)
			(end 2.3876 -4.826)
			(stroke
				(width 0.1524)
				(type default)
			)
			(layer "B.SilkS")
		)
		(fp_line
			(start -2.3622 -4.826)
			(end -2.3622 3.4798)
			(stroke
				(width 0.1524)
				(type default)
			)
			(layer "B.SilkS")
		)
		(fp_line
			(start 2.3876 -4.826)
			(end -2.3622 -4.826)
			(stroke
				(width 0.1524)
				(type default)
			)
			(layer "B.SilkS")
		)
		(fp_rect
			(start 2.6416 3.7338)
			(end -2.6162 -5.08)
			(stroke
				(width 0)
				(type default)
			)
			(fill no)
			(layer "B.CrtYd")
		)
		(fp_rect
			(start 2.6416 3.7338)
			(end -2.6162 -5.08)
			(stroke
				(width 0)
				(type default)
			)
			(fill no)
			(layer "B.Fab")
		)
		(pad "1" smd circle
			(at -0.496824 -1.301496 90)
			(size 0.6604 0.6604)
			(layers "B.Cu" "B.Mask" "B.Paste")
			(net "L5_85OHM_10INCH_DP")
		)
		(pad "2" smd circle
			(at 0.503936 -1.301496 90)
			(size 0.6604 0.6604)
			(layers "B.Cu" "B.Mask" "B.Paste")
			(net "L5_85OHM_10INCH_DN")
		)
		(pad "3" smd custom
			(at 0.00889 0.370078 90)
			(size 0.74295 0.74295)
			(layers "B.Cu" "B.Mask" "B.Paste")
			(net "GND")
			(options
				(clearance outline)
				(anchor circle)
			)
			(primitives
				(gr_poly
					(pts
						(xy -2.1209 -1.4859) (xy 2.1209 -1.4859) (xy 2.1209 1.4859) (xy 1.08585 1.4859) (xy 1.08585 0.4699)
						(xy -1.08585 0.4699) (xy -1.08585 1.4859) (xy -2.1209 1.4859)
					)
					(width 0)
					(fill yes)
				)
			)
		)
		(pad "4" thru_hole circle
			(at -1.266444 -3.851656 90)
			(size 1.4478 1.4478)
			(drill 1.0414)
			(layers "*.Cu" "*.Mask")
			(remove_unused_layers no)
			(net "GND")
			(clearance 0.1524)
			(thermal_gap 0.1524)
		)
		(pad "5" thru_hole circle
			(at 1.273556 -3.851656 90)
			(size 1.4478 1.4478)
			(drill 1.0414)
			(layers "*.Cu" "*.Mask")
			(remove_unused_layers no)
			(net "GND")
			(clearance 0.1524)
			(thermal_gap 0.1524)
		)
		(pad "6" thru_hole circle
			(at -1.266444 2.498344 90)
			(size 1.4478 1.4478)
			(drill 1.0414)
			(layers "*.Cu" "*.Mask")
			(remove_unused_layers no)
			(net "GND")
			(clearance 0.1524)
			(thermal_gap 0.1524)
		)
		(pad "7" thru_hole circle
			(at 1.273556 2.498344 90)
			(size 1.4478 1.4478)
			(drill 1.0414)
			(layers "*.Cu" "*.Mask")
			(remove_unused_layers no)
			(net "GND")
			(clearance 0.1524)
			(thermal_gap 0.1524)
		)
		(pad "8" thru_hole circle
			(at -1.27 -0.4572 90)
			(size 0.7112 0.7112)
			(drill 0.4064)
			(layers "*.Cu" "*.Mask")
			(remove_unused_layers no)
			(net "GND")
			(clearance 0.1016)
			(thermal_gap 0.1016)
		)
		(pad "9" thru_hole circle
			(at -1.27 0.762 90)
			(size 0.7112 0.7112)
			(drill 0.4064)
			(layers "*.Cu" "*.Mask")
			(remove_unused_layers no)
			(net "GND")
			(clearance 0.1016)
			(thermal_gap 0.1016)
		)
		(pad "10" thru_hole circle
			(at 0.0254 0.762 90)
			(size 0.7112 0.7112)
			(drill 0.4064)
			(layers "*.Cu" "*.Mask")
			(remove_unused_layers no)
			(net "GND")
			(clearance 0.1016)
			(thermal_gap 0.1016)
		)
		(pad "11" thru_hole circle
			(at 1.27 0.762 90)
			(size 0.7112 0.7112)
			(drill 0.4064)
			(layers "*.Cu" "*.Mask")
			(remove_unused_layers no)
			(net "GND")
			(clearance 0.1016)
			(thermal_gap 0.1016)
		)
		(pad "12" thru_hole circle
			(at 1.27 -0.4572 90)
			(size 0.7112 0.7112)
			(drill 0.4064)
			(layers "*.Cu" "*.Mask")
			(remove_unused_layers no)
			(net "GND")
			(clearance 0.1016)
			(thermal_gap 0.1016)
		)
	)
)
